# Antmicro Baseboard for Jetson AGX Thor — KiCad project settings (.kicad_pro: net classes, design rules, text variables)
{
  "board": {
    "3dviewports": [
      {
        "name": "TOP",
        "ww": 1.0,
        "wx": -8.277483940124512,
        "wy": 8.277483940124512,
        "wz": -16.0,
        "xw": 0.0,
        "xx": 1.0,
        "xy": 0.0,
        "xz": 0.0,
        "yw": 0.0,
        "yx": 0.0,
        "yy": 1.0,
        "yz": 0.0,
        "zw": 0.0,
        "zx": 0.0,
        "zy": 0.0,
        "zz": 1.0
      }
    ],
    "design_settings": {
      "defaults": {
        "apply_defaults_to_fp_fields": false,
        "apply_defaults_to_fp_shapes": false,
        "apply_defaults_to_fp_text": false,
        "board_outline_line_width": 0.1,
        "copper_line_width": 0.2,
        "copper_text_italic": false,
        "copper_text_size_h": 1.5,
        "copper_text_size_v": 1.5,
        "copper_text_thickness": 0.3,
        "copper_text_upright": false,
        "courtyard_line_width": 0.05,
        "dimension_precision": 4,
        "dimension_units": 3,
        "dimensions": {
          "arrow_length": 1270000,
          "extension_offset": 500000,
          "keep_text_aligned": true,
          "suppress_zeroes": true,
          "text_position": 0,
          "units_format": 0
        },
        "fab_line_width": 0.1,
        "fab_text_italic": false,
        "fab_text_size_h": 1.0,
        "fab_text_size_v": 1.0,
        "fab_text_thickness": 0.15,
        "fab_text_upright": false,
        "other_line_width": 0.15,
        "other_text_italic": false,
        "other_text_size_h": 1.0,
        "other_text_size_v": 1.0,
        "other_text_thickness": 0.15,
        "other_text_upright": false,
        "pads": {
          "drill": 0.8,
          "height": 1.27,
          "width": 2.54
        },
        "silk_line_width": 0.15,
        "silk_text_italic": false,
        "silk_text_size_h": 1.0,
        "silk_text_size_v": 1.0,
        "silk_text_thickness": 0.15,
        "silk_text_upright": false,
        "zones": {
          "min_clearance": 0.25
        }
      },
      "diff_pair_dimensions": [
        {
          "gap": 0.0,
          "via_gap": 0.0,
          "width": 0.0
        }
      ],
      "drc_exclusions": [],
      "meta": {
        "version": 2
      },
      "rule_severities": {
        "annular_width": "error",
        "clearance": "error",
        "connection_width": "warning",
        "copper_edge_clearance": "error",
        "copper_sliver": "warning",
        "courtyards_overlap": "error",
        "creepage": "error",
        "diff_pair_gap_out_of_range": "error",
        "diff_pair_uncoupled_length_too_long": "error",
        "drill_out_of_range": "error",
        "duplicate_footprints": "warning",
        "extra_footprint": "warning",
        "footprint": "error",
        "footprint_filters_mismatch": "ignore",
        "footprint_symbol_mismatch": "warning",
        "footprint_type_mismatch": "ignore",
        "hole_clearance": "error",
        "hole_to_hole": "error",
        "holes_co_located": "error",
        "invalid_outline": "error",
        "isolated_copper": "warning",
        "item_on_disabled_layer": "error",
        "items_not_allowed": "error",
        "length_out_of_range": "error",
        "lib_footprint_issues": "warning",
        "lib_footprint_mismatch": "ignore",
        "malformed_courtyard": "error",
        "microvia_drill_out_of_range": "error",
        "mirrored_text_on_front_layer": "warning",
        "missing_courtyard": "warning",
        "missing_footprint": "warning",
        "net_conflict": "warning",
        "nonmirrored_text_on_back_layer": "warning",
        "npth_inside_courtyard": "warning",
        "padstack": "error",
        "pth_inside_courtyard": "warning",
        "shorting_items": "error",
        "silk_edge_clearance": "warning",
        "silk_over_copper": "warning",
        "silk_overlap": "warning",
        "skew_out_of_range": "error",
        "solder_mask_bridge": "error",
        "starved_thermal": "error",
        "text_height": "warning",
        "text_on_edge_cuts": "error",
        "text_thickness": "warning",
        "through_hole_pad_without_hole": "error",
        "too_many_vias": "error",
        "track_angle": "error",
        "track_dangling": "warning",
        "track_segment_length": "error",
        "track_width": "error",
        "tracks_crossing": "error",
        "unconnected_items": "error",
        "unresolved_variable": "error",
        "via_dangling": "warning",
        "zones_intersect": "error"
      },
      "rules": {
        "max_error": 0.005,
        "min_clearance": 0.1,
        "min_connection": 0.1,
        "min_copper_edge_clearance": 0.4,
        "min_groove_width": 0.0,
        "min_hole_clearance": 0.22,
        "min_hole_to_hole": 0.25,
        "min_microvia_diameter": 0.2,
        "min_microvia_drill": 0.1,
        "min_resolved_spokes": 1,
        "min_silk_clearance": 0.0,
        "min_text_height": 0.6,
        "min_text_thickness": 0.0,
        "min_through_hole_diameter": 0.1,
        "min_track_width": 0.1,
        "min_via_annular_width": 0.125,
        "min_via_diameter": 0.45,
        "solder_mask_to_copper_clearance": 0.0,
        "use_height_for_length_calcs": true
      },
      "teardrop_options": [
        {
          "td_onpthpad": false,
          "td_onroundshapesonly": false,
          "td_onsmdpad": false,
          "td_ontrackend": true,
          "td_onvia": false
        }
      ],
      "teardrop_parameters": [
        {
          "td_allow_use_two_tracks": true,
          "td_curve_segcount": 0,
          "td_height_ratio": 1.0,
          "td_length_ratio": 0.5,
          "td_maxheight": 2.0,
          "td_maxlen": 1.0,
          "td_on_pad_in_zone": false,
          "td_target_name": "td_round_shape",
          "td_width_to_size_filter_ratio": 0.9
        },
        {
          "td_allow_use_two_tracks": true,
          "td_curve_segcount": 0,
          "td_height_ratio": 1.0,
          "td_length_ratio": 0.5,
          "td_maxheight": 2.0,
          "td_maxlen": 1.0,
          "td_on_pad_in_zone": false,
          "td_target_name": "td_rect_shape",
          "td_width_to_size_filter_ratio": 0.9
        },
        {
          "td_allow_use_two_tracks": true,
          "td_curve_segcount": 0,
          "td_height_ratio": 1.0,
          "td_length_ratio": 0.5,
          "td_maxheight": 2.0,
          "td_maxlen": 1.0,
          "td_on_pad_in_zone": false,
          "td_target_name": "td_track_end",
          "td_width_to_size_filter_ratio": 0.9
        }
      ],
      "track_widths": [
        0.0,
        0.1,
        0.15,
        0.2,
        0.3,
        0.5,
        0.75,
        1.0,
        1.5,
        2.0
      ],
      "tuning_pattern_settings": {
        "diff_pair_defaults": {
          "corner_radius_percentage": 80,
          "corner_style": 1,
          "max_amplitude": 1.0,
          "min_amplitude": 0.2,
          "single_sided": false,
          "spacing": 1.0
        },
        "diff_pair_skew_defaults": {
          "corner_radius_percentage": 80,
          "corner_style": 1,
          "max_amplitude": 1.0,
          "min_amplitude": 0.2,
          "single_sided": false,
          "spacing": 0.6
        },
        "single_track_defaults": {
          "corner_radius_percentage": 80,
          "corner_style": 1,
          "max_amplitude": 1.0,
          "min_amplitude": 0.2,
          "single_sided": false,
          "spacing": 0.6
        }
      },
      "via_dimensions": [
        {
          "diameter": 0.0,
          "drill": 0.0
        },
        {
          "diameter": 0.45,
          "drill": 0.1
        },
        {
          "diameter": 1.0,
          "drill": 0.5
        }
      ],
      "zones_allow_external_fillets": false
    },
    "ipc2581": {
      "dist": "",
      "distpn": "",
      "internal_id": "",
      "mfg": "",
      "mpn": ""
    },
    "layer_pairs": [],
    "layer_presets": [],
    "viewports": []
  },
  "boards": [],
  "cvpcb": {
    "equivalence_files": []
  },
  "erc": {
    "erc_exclusions": [],
    "meta": {
      "version": 0
    },
    "pin_map": [
      [
        0,
        0,
        0,
        0,
        0,
        0,
        1,
        0,
        0,
        0,
        0,
        2
      ],
      [
        0,
        2,
        0,
        1,
        0,
        0,
        1,
        0,
        2,
        2,
        2,
        2
      ],
      [
        0,
        0,
        0,
        0,
        0,
        0,
        1,
        0,
        1,
        0,
        1,
        2
      ],
      [
        0,
        1,
        0,
        0,
        0,
        0,
        1,
        1,
        2,
        1,
        1,
        2
      ],
      [
        0,
        0,
        0,
        0,
        0,
        0,
        1,
        0,
        0,
        0,
        0,
        2
      ],
      [
        0,
        0,
        0,
        0,
        0,
        0,
        0,
        0,
        0,
        0,
        0,
        2
      ],
      [
        1,
        1,
        1,
        1,
        1,
        0,
        1,
        1,
        1,
        1,
        1,
        2
      ],
      [
        0,
        0,
        0,
        1,
        0,
        0,
        1,
        0,
        0,
        0,
        0,
        2
      ],
      [
        0,
        2,
        1,
        2,
        0,
        0,
        1,
        0,
        2,
        2,
        2,
        2
      ],
      [
        0,
        2,
        0,
        1,
        0,
        0,
        1,
        0,
        2,
        0,
        0,
        2
      ],
      [
        0,
        2,
        1,
        1,
        0,
        0,
        1,
        0,
        2,
        0,
        0,
        2
      ],
      [
        2,
        2,
        2,
        2,
        2,
        2,
        2,
        2,
        2,
        2,
        2,
        2
      ]
    ],
    "rule_severities": {
      "bus_definition_conflict": "error",
      "bus_entry_needed": "error",
      "bus_to_bus_conflict": "error",
      "bus_to_net_conflict": "error",
      "different_unit_footprint": "error",
      "different_unit_net": "error",
      "duplicate_reference": "error",
      "duplicate_sheet_names": "error",
      "endpoint_off_grid": "warning",
      "extra_units": "error",
      "footprint_filter": "ignore",
      "footprint_link_issues": "warning",
      "four_way_junction": "ignore",
      "global_label_dangling": "warning",
      "hier_label_mismatch": "error",
      "label_dangling": "error",
      "label_multiple_wires": "warning",
      "lib_symbol_issues": "warning",
      "lib_symbol_mismatch": "ignore",
      "missing_bidi_pin": "warning",
      "missing_input_pin": "warning",
      "missing_power_pin": "error",
      "missing_unit": "warning",
      "multiple_net_names": "warning",
      "net_not_bus_member": "warning",
      "no_connect_connected": "warning",
      "no_connect_dangling": "warning",
      "pin_not_connected": "error",
      "pin_not_driven": "error",
      "pin_to_pin": "error",
      "power_pin_not_driven": "error",
      "same_local_global_label": "warning",
      "similar_label_and_power": "warning",
      "similar_labels": "warning",
      "similar_power": "warning",
      "simulation_model_issue": "ignore",
      "single_global_label": "ignore",
      "unannotated": "error",
      "unconnected_wire_endpoint": "warning",
      "undefined_netclass": "error",
      "unit_value_mismatch": "error",
      "unresolved_variable": "error",
      "wire_dangling": "error"
    }
  },
  "libraries": {
    "pinned_footprint_libs": [],
    "pinned_symbol_libs": []
  },
  "meta": {
    "filename": "jetson-agx-thor-baseboard.kicad_pro",
    "version": 3
  },
  "net_settings": {
    "classes": [
      {
        "bus_width": 12,
        "clearance": 0.1,
        "diff_pair_gap": 5.0,
        "diff_pair_via_gap": 0.25,
        "diff_pair_width": 5.0,
        "line_style": 0,
        "microvia_diameter": 0.45,
        "microvia_drill": 0.1,
        "name": "Default",
        "pcb_color": "rgba(0, 0, 0, 0.000)",
        "priority": 2147483647,
        "schematic_color": "rgba(0, 0, 0, 0.000)",
        "track_width": 0.1,
        "via_diameter": 0.45,
        "via_drill": 0.1,
        "wire_width": 6
      },
      {
        "bus_width": 12,
        "line_style": 0,
        "name": "85Ohm-diff_DP",
        "pcb_color": "rgb(0, 255, 0)",
        "priority": 1,
        "schematic_color": "rgba(0, 0, 0, 0.000)",
        "wire_width": 6
      },
      {
        "bus_width": 12,
        "line_style": 0,
        "name": "85Ohm-diff_PCIE",
        "pcb_color": "rgb(255, 0, 255)",
        "priority": 3,
        "schematic_color": "rgba(0, 0, 0, 0.000)",
        "wire_width": 6
      },
      {
        "bus_width": 12,
        "line_style": 0,
        "name": "85Ohm-diff_SFI",
        "pcb_color": "rgb(194, 194, 0)",
        "priority": 0,
        "schematic_color": "rgba(0, 0, 0, 0.000)",
        "wire_width": 6
      },
      {
        "bus_width": 12,
        "line_style": 0,
        "name": "85Ohm-diff_USB_SS",
        "pcb_color": "rgb(0, 0, 255)",
        "priority": 5,
        "schematic_color": "rgba(0, 0, 0, 0.000)",
        "wire_width": 6
      },
      {
        "bus_width": 12,
        "line_style": 0,
        "name": "90Ohm-diff_CSI",
        "pcb_color": "rgb(0, 255, 255)",
        "priority": 2,
        "schematic_color": "rgba(0, 0, 0, 0.000)",
        "wire_width": 6
      },
      {
        "bus_width": 12,
        "line_style": 0,
        "name": "90Ohm-diff_USB_2.0",
        "pcb_color": "rgb(0, 0, 194)",
        "priority": 4,
        "schematic_color": "rgba(0, 0, 0, 0.000)",
        "wire_width": 6
      }
    ],
    "meta": {
      "version": 4
    },
    "net_colors": null,
    "netclass_assignments": {
      "/CSI/CAM0.CSI0_CLK+": [
        "90Ohm-diff_CSI"
      ],
      "/CSI/CAM0.CSI0_CLK-": [
        "90Ohm-diff_CSI"
      ],
      "/CSI/CAM0.CSI0_D0+": [
        "90Ohm-diff_CSI"
      ],
      "/CSI/CAM0.CSI0_D0-": [
        "90Ohm-diff_CSI"
      ],
      "/CSI/CAM0.CSI0_D1+": [
        "90Ohm-diff_CSI"
      ],
      "/CSI/CAM0.CSI0_D1-": [
        "90Ohm-diff_CSI"
      ],
      "/CSI/CAM0.CSI1_D0+": [
        "90Ohm-diff_CSI"
      ],
      "/CSI/CAM0.CSI1_D0-": [
        "90Ohm-diff_CSI"
      ],
      "/CSI/CAM0.CSI1_D1+": [
        "90Ohm-diff_CSI"
      ],
      "/CSI/CAM0.CSI1_D1-": [
        "90Ohm-diff_CSI"
      ],
      "/CSI/CAM0.CSI2_CLK+": [
        "90Ohm-diff_CSI"
      ],
      "/CSI/CAM0.CSI2_CLK-": [
        "90Ohm-diff_CSI"
      ],
      "/CSI/CAM0.CSI2_D0+": [
        "90Ohm-diff_CSI"
      ],
      "/CSI/CAM0.CSI2_D0-": [
        "90Ohm-diff_CSI"
      ],
      "/CSI/CAM0.CSI2_D1+": [
        "90Ohm-diff_CSI"
      ],
      "/CSI/CAM0.CSI2_D1-": [
        "90Ohm-diff_CSI"
      ],
      "/CSI/CAM0.CSI3_D0+": [
        "90Ohm-diff_CSI"
      ],
      "/CSI/CAM0.CSI3_D0-": [
        "90Ohm-diff_CSI"
      ],
      "/CSI/CAM0.CSI3_D1+": [
        "90Ohm-diff_CSI"
      ],
      "/CSI/CAM0.CSI3_D1-": [
        "90Ohm-diff_CSI"
      ],
      "/CSI/CAM1.CSI0_CLK+": [
        "90Ohm-diff_CSI"
      ],
      "/CSI/CAM1.CSI0_CLK-": [
        "90Ohm-diff_CSI"
      ],
      "/CSI/CAM1.CSI0_D0+": [
        "90Ohm-diff_CSI"
      ],
      "/CSI/CAM1.CSI0_D0-": [
        "90Ohm-diff_CSI"
      ],
      "/CSI/CAM1.CSI0_D1+": [
        "90Ohm-diff_CSI"
      ],
      "/CSI/CAM1.CSI0_D1-": [
        "90Ohm-diff_CSI"
      ],
      "/CSI/CAM1.CSI1_D0+": [
        "90Ohm-diff_CSI"
      ],
      "/CSI/CAM1.CSI1_D0-": [
        "90Ohm-diff_CSI"
      ],
      "/CSI/CAM1.CSI1_D1+": [
        "90Ohm-diff_CSI"
      ],
      "/CSI/CAM1.CSI1_D1-": [
        "90Ohm-diff_CSI"
      ],
      "/CSI/CAM1.CSI2_CLK+": [
        "90Ohm-diff_CSI"
      ],
      "/CSI/CAM1.CSI2_CLK-": [
        "90Ohm-diff_CSI"
      ],
      "/CSI/CAM1.CSI2_D0+": [
        "90Ohm-diff_CSI"
      ],
      "/CSI/CAM1.CSI2_D0-": [
        "90Ohm-diff_CSI"
      ],
      "/CSI/CAM1.CSI2_D1+": [
        "90Ohm-diff_CSI"
      ],
      "/CSI/CAM1.CSI2_D1-": [
        "90Ohm-diff_CSI"
      ],
      "/CSI/CAM1.CSI3_D0+": [
        "90Ohm-diff_CSI"
      ],
      "/CSI/CAM1.CSI3_D0-": [
        "90Ohm-diff_CSI"
      ],
      "/CSI/CAM1.CSI3_D1+": [
        "90Ohm-diff_CSI"
      ],
      "/CSI/CAM1.CSI3_D1-": [
        "90Ohm-diff_CSI"
      ],
      "/CSI/CAM2.CSI4_CLK+": [
        "90Ohm-diff_CSI"
      ],
      "/CSI/CAM2.CSI4_CLK-": [
        "90Ohm-diff_CSI"
      ],
      "/CSI/CAM2.CSI4_D0+": [
        "90Ohm-diff_CSI"
      ],
      "/CSI/CAM2.CSI4_D0-": [
        "90Ohm-diff_CSI"
      ],
      "/CSI/CAM2.CSI4_D1+": [
        "90Ohm-diff_CSI"
      ],
      "/CSI/CAM2.CSI4_D1-": [
        "90Ohm-diff_CSI"
      ],
      "/CSI/CAM2.CSI5_D0+": [
        "90Ohm-diff_CSI"
      ],
      "/CSI/CAM2.CSI5_D0-": [
        "90Ohm-diff_CSI"
      ],
      "/CSI/CAM2.CSI5_D1+": [
        "90Ohm-diff_CSI"
      ],
      "/CSI/CAM2.CSI5_D1-": [
        "90Ohm-diff_CSI"
      ],
      "/CSI/CAM3.CSI6_CLK+": [
        "90Ohm-diff_CSI"
      ],
      "/CSI/CAM3.CSI6_CLK-": [
        "90Ohm-diff_CSI"
      ],
      "/CSI/CAM3.CSI6_D0+": [
        "90Ohm-diff_CSI"
      ],
      "/CSI/CAM3.CSI6_D0-": [
        "90Ohm-diff_CSI"
      ],
      "/CSI/CAM3.CSI6_D1+": [
        "90Ohm-diff_CSI"
      ],
      "/CSI/CAM3.CSI6_D1-": [
        "90Ohm-diff_CSI"
      ],
      "/CSI/CAM3.CSI7_D0+": [
        "90Ohm-diff_CSI"
      ],
      "/CSI/CAM3.CSI7_D0-": [
        "90Ohm-diff_CSI"
      ],
      "/CSI/CAM3.CSI7_D1+": [
        "90Ohm-diff_CSI"
      ],
      "/CSI/CAM3.CSI7_D1-": [
        "90Ohm-diff_CSI"
      ],
      "/CSI/CSI0.CLK+": [
        "95Ohm-diff_CSI"
      ],
      "/CSI/CSI0.CLK-": [
        "95Ohm-diff_CSI"
      ],
      "/CSI/CSI0.D0+": [
        "95Ohm-diff_CSI"
      ],
      "/CSI/CSI0.D0-": [
        "95Ohm-diff_CSI"
      ],
      "/CSI/CSI0.D1+": [
        "95Ohm-diff_CSI"
      ],
      "/CSI/CSI0.D1-": [
        "95Ohm-diff_CSI"
      ],
      "/CSI/CSI0.D2+": [
        "95Ohm-diff_CSI"
      ],
      "/CSI/CSI0.D2-": [
        "95Ohm-diff_CSI"
      ],
      "/CSI/CSI0.D3+": [
        "95Ohm-diff_CSI"
      ],
      "/CSI/CSI0.D3-": [
        "95Ohm-diff_CSI"
      ],
      "/CSI/CSI1.CLK+": [
        "95Ohm-diff_CSI"
      ],
      "/CSI/CSI1.CLK-": [
        "95Ohm-diff_CSI"
      ],
      "/CSI/CSI1.D0+": [
        "95Ohm-diff_CSI"
      ],
      "/CSI/CSI1.D0-": [
        "95Ohm-diff_CSI"
      ],
      "/CSI/CSI1.D1+": [
        "95Ohm-diff_CSI"
      ],
      "/CSI/CSI1.D1-": [
        "95Ohm-diff_CSI"
      ],
      "/CSI/CSI1.D2+": [
        "95Ohm-diff_CSI"
      ],
      "/CSI/CSI1.D2-": [
        "95Ohm-diff_CSI"
      ],
      "/CSI/CSI1.D3+": [
        "95Ohm-diff_CSI"
      ],
      "/CSI/CSI1.D3-": [
        "95Ohm-diff_CSI"
      ],
      "/CSI/CSI2.CLK+": [
        "95Ohm-diff_CSI"
      ],
      "/CSI/CSI2.CLK-": [
        "95Ohm-diff_CSI"
      ],
      "/CSI/CSI2.D0+": [
        "95Ohm-diff_CSI"
      ],
      "/CSI/CSI2.D0-": [
        "95Ohm-diff_CSI"
      ],
      "/CSI/CSI2.D1+": [
        "95Ohm-diff_CSI"
      ],
      "/CSI/CSI2.D1-": [
        "95Ohm-diff_CSI"
      ],
      "/CSI/CSI2.D2+": [
        "95Ohm-diff_CSI"
      ],
      "/CSI/CSI2.D2-": [
        "95Ohm-diff_CSI"
      ],
      "/CSI/CSI2.D3+": [
        "95Ohm-diff_CSI"
      ],
      "/CSI/CSI2.D3-": [
        "95Ohm-diff_CSI"
      ],
      "/CSI/CSI3.CLK+": [
        "95Ohm-diff_CSI"
      ],
      "/CSI/CSI3.CLK-": [
        "95Ohm-diff_CSI"
      ],
      "/CSI/CSI3.D0+": [
        "95Ohm-diff_CSI"
      ],
      "/CSI/CSI3.D0-": [
        "95Ohm-diff_CSI"
      ],
      "/CSI/CSI3.D1+": [
        "95Ohm-diff_CSI"
      ],
      "/CSI/CSI3.D1-": [
        "95Ohm-diff_CSI"
      ],
      "/CSI/CSI3.D2+": [
        "95Ohm-diff_CSI"
      ],
      "/CSI/CSI3.D2-": [
        "95Ohm-diff_CSI"
      ],
      "/CSI/CSI3.D3+": [
        "95Ohm-diff_CSI"
      ],
      "/CSI/CSI3.D3-": [
        "95Ohm-diff_CSI"
      ],
      "/Expansion connector/DP1.AUX+": [
        "85Ohm-diff_DP"
      ],
      "/Expansion connector/DP1.AUX-": [
        "85Ohm-diff_DP"
      ],
      "/Expansion connector/DP1.HPD": [
        "85Ohm-diff_DP"
      ],
      "/Expansion connector/DP1.TX0+": [
        "85Ohm-diff_DP"
      ],
      "/Expansion connector/DP1.TX0-": [
        "85Ohm-diff_DP"
      ],
      "/Expansion connector/DP1.TX1+": [
        "85Ohm-diff_DP"
      ],
      "/Expansion connector/DP1.TX1-": [
        "85Ohm-diff_DP"
      ],
      "/Expansion connector/DP1.TX2+": [
        "85Ohm-diff_DP"
      ],
      "/Expansion connector/DP1.TX2-": [
        "85Ohm-diff_DP"
      ],
      "/Expansion connector/DP1.TX3+": [
        "85Ohm-diff_DP"
      ],
      "/Expansion connector/DP1.TX3-": [
        "85Ohm-diff_DP"
      ],
      "/Expansion connector/DP1{DP}": [
        "85Ohm-diff_DP"
      ],
      "/Expansion connector/DP2.AUX+": [
        "85Ohm-diff_DP"
      ],
      "/Expansion connector/DP2.AUX-": [
        "85Ohm-diff_DP"
      ],
      "/Expansion connector/DP2.HPD": [
        "85Ohm-diff_DP"
      ],
      "/Expansion connector/DP2.TX0+": [
        "85Ohm-diff_DP"
      ],
      "/Expansion connector/DP2.TX0-": [
        "85Ohm-diff_DP"
      ],
      "/Expansion connector/DP2.TX1+": [
        "85Ohm-diff_DP"
      ],
      "/Expansion connector/DP2.TX1-": [
        "85Ohm-diff_DP"
      ],
      "/Expansion connector/DP2.TX2+": [
        "85Ohm-diff_DP"
      ],
      "/Expansion connector/DP2.TX2-": [
        "85Ohm-diff_DP"
      ],
      "/Expansion connector/DP2.TX3+": [
        "85Ohm-diff_DP"
      ],
      "/Expansion connector/DP2.TX3-": [
        "85Ohm-diff_DP"
      ],
      "/Expansion connector/DP2{DP}": [
        "85Ohm-diff_DP"
      ],
      "/Expansion connector/DP3.AUX+": [
        "85Ohm-diff_DP"
      ],
      "/Expansion connector/DP3.AUX-": [
        "85Ohm-diff_DP"
      ],
      "/Expansion connector/DP3.HPD": [
        "85Ohm-diff_DP"
      ],
      "/Expansion connector/DP3.TX0+": [
        "85Ohm-diff_DP"
      ],
      "/Expansion connector/DP3.TX0-": [
        "85Ohm-diff_DP"
      ],
      "/Expansion connector/DP3.TX1+": [
        "85Ohm-diff_DP"
      ],
      "/Expansion connector/DP3.TX1-": [
        "85Ohm-diff_DP"
      ],
      "/Expansion connector/DP3.TX2+": [
        "85Ohm-diff_DP"
      ],
      "/Expansion connector/DP3.TX2-": [
        "85Ohm-diff_DP"
      ],
      "/Expansion connector/DP3.TX3+": [
        "85Ohm-diff_DP"
      ],
      "/Expansion connector/DP3.TX3-": [
        "85Ohm-diff_DP"
      ],
      "/Expansion connector/DP3{DP}": [
        "85Ohm-diff_DP"
      ],
      "/Expansion connector/PCIe_{C2x1}.CLK+": [
        "85Ohm-diff_PCIE"
      ],
      "/Expansion connector/PCIe_{C2x1}.CLK-": [
        "85Ohm-diff_PCIE"
      ],
      "/Expansion connector/PCIe_{C2x1}.RX0+": [
        "85Ohm-diff_PCIE"
      ],
      "/Expansion connector/PCIe_{C2x1}.RX0-": [
        "85Ohm-diff_PCIE"
      ],
      "/Expansion connector/PCIe_{C2x1}.TX0+": [
        "85Ohm-diff_PCIE"
      ],
      "/Expansion connector/PCIe_{C2x1}.TX0-": [
        "85Ohm-diff_PCIE"
      ],
      "/Expansion connector/PCIe_{C3x2}.CLK+": [
        "85Ohm-diff_PCIE"
      ],
      "/Expansion connector/PCIe_{C3x2}.CLK-": [
        "85Ohm-diff_PCIE"
      ],
      "/Expansion connector/PCIe_{C3x2}.RX0+": [
        "85Ohm-diff_PCIE"
      ],
      "/Expansion connector/PCIe_{C3x2}.RX0-": [
        "85Ohm-diff_PCIE"
      ],
      "/Expansion connector/PCIe_{C3x2}.RX1+": [
        "85Ohm-diff_PCIE"
      ],
      "/Expansion connector/PCIe_{C3x2}.RX1-": [
        "85Ohm-diff_PCIE"
      ],
      "/Expansion connector/PCIe_{C3x2}.TX0+": [
        "85Ohm-diff_PCIE"
      ],
      "/Expansion connector/PCIe_{C3x2}.TX0-": [
        "85Ohm-diff_PCIE"
      ],
      "/Expansion connector/PCIe_{C3x2}.TX1+": [
        "85Ohm-diff_PCIE"
      ],
      "/Expansion connector/PCIe_{C3x2}.TX1-": [
        "85Ohm-diff_PCIE"
      ],
      "/Expansion connector/PER0_C2_N": [
        "85Ohm-diff_PCIE"
      ],
      "/Expansion connector/PER0_C2_P": [
        "85Ohm-diff_PCIE"
      ],
      "/Expansion connector/PET0_C2_N": [
        "85Ohm-diff_PCIE"
      ],
      "/Expansion connector/PET0_C2_P": [
        "85Ohm-diff_PCIE"
      ],
      "/Expansion connector/PET0_C3_N": [
        "85Ohm-diff_PCIE"
      ],
      "/Expansion connector/PET0_C3_P": [
        "85Ohm-diff_PCIE"
      ],
      "/Expansion connector/PET1_C3_N": [
        "85Ohm-diff_PCIE"
      ],
      "/Expansion connector/PET1_C3_P": [
        "85Ohm-diff_PCIE"
      ],
      "/M.2/M2_E_PET0_N": [
        "85Ohm-diff_PCIE"
      ],
      "/M.2/M2_E_PET0_P": [
        "85Ohm-diff_PCIE"
      ],
      "/M.2/M2_M_PET0_N": [
        "85Ohm-diff_PCIE"
      ],
      "/M.2/M2_M_PET0_P": [
        "85Ohm-diff_PCIE"
      ],
      "/M.2/M2_M_PET1_N": [
        "85Ohm-diff_PCIE"
      ],
      "/M.2/M2_M_PET1_P": [
        "85Ohm-diff_PCIE"
      ],
      "/M.2/M2_M_PET2_N": [
        "85Ohm-diff_PCIE"
      ],
      "/M.2/M2_M_PET2_P": [
        "85Ohm-diff_PCIE"
      ],
      "/M.2/M2_M_PET3_N": [
        "85Ohm-diff_PCIE"
      ],
      "/M.2/M2_M_PET3_P": [
        "85Ohm-diff_PCIE"
      ],
      "/M.2/PCIe_{C1x1}.CLK+": [
        "85Ohm-diff_PCIE"
      ],
      "/M.2/PCIe_{C1x1}.CLK-": [
        "85Ohm-diff_PCIE"
      ],
      "/M.2/PCIe_{C1x1}.RX0+": [
        "85Ohm-diff_PCIE"
      ],
      "/M.2/PCIe_{C1x1}.RX0-": [
        "85Ohm-diff_PCIE"
      ],
      "/M.2/PCIe_{C1x1}.RX1+": [
        "85Ohm-diff_PCIE"
      ],
      "/M.2/PCIe_{C1x1}.RX1-": [
        "85Ohm-diff_PCIE"
      ],
      "/M.2/PCIe_{C1x1}.RX2+": [
        "85Ohm-diff_PCIE"
      ],
      "/M.2/PCIe_{C1x1}.RX2-": [
        "85Ohm-diff_PCIE"
      ],
      "/M.2/PCIe_{C1x1}.RX3+": [
        "85Ohm-diff_PCIE"
      ],
      "/M.2/PCIe_{C1x1}.RX3-": [
        "85Ohm-diff_PCIE"
      ],
      "/M.2/PCIe_{C1x1}.RX4+": [
        "85Ohm-diff_PCIE"
      ],
      "/M.2/PCIe_{C1x1}.RX4-": [
        "85Ohm-diff_PCIE"
      ],
      "/M.2/PCIe_{C1x1}.RX5+": [
        "85Ohm-diff_PCIE"
      ],
      "/M.2/PCIe_{C1x1}.RX5-": [
        "85Ohm-diff_PCIE"
      ],
      "/M.2/PCIe_{C1x1}.RX6+": [
        "85Ohm-diff_PCIE"
      ],
      "/M.2/PCIe_{C1x1}.RX6-": [
        "85Ohm-diff_PCIE"
      ],
      "/M.2/PCIe_{C1x1}.RX7+": [
        "85Ohm-diff_PCIE"
      ],
      "/M.2/PCIe_{C1x1}.RX7-": [
        "85Ohm-diff_PCIE"
      ],
      "/M.2/PCIe_{C1x1}.TX0+": [
        "85Ohm-diff_PCIE"
      ],
      "/M.2/PCIe_{C1x1}.TX0-": [
        "85Ohm-diff_PCIE"
      ],
      "/M.2/PCIe_{C1x1}.TX1+": [
        "85Ohm-diff_PCIE"
      ],
      "/M.2/PCIe_{C1x1}.TX1-": [
        "85Ohm-diff_PCIE"
      ],
      "/M.2/PCIe_{C1x1}.TX2+": [
        "85Ohm-diff_PCIE"
      ],
      "/M.2/PCIe_{C1x1}.TX2-": [
        "85Ohm-diff_PCIE"
      ],
      "/M.2/PCIe_{C1x1}.TX3+": [
        "85Ohm-diff_PCIE"
      ],
      "/M.2/PCIe_{C1x1}.TX3-": [
        "85Ohm-diff_PCIE"
      ],
      "/M.2/PCIe_{C1x1}.TX4+": [
        "85Ohm-diff_PCIE"
      ],
      "/M.2/PCIe_{C1x1}.TX4-": [
        "85Ohm-diff_PCIE"
      ],
      "/M.2/PCIe_{C1x1}.TX5+": [
        "85Ohm-diff_PCIE"
      ],
      "/M.2/PCIe_{C1x1}.TX5-": [
        "85Ohm-diff_PCIE"
      ],
      "/M.2/PCIe_{C1x1}.TX6+": [
        "85Ohm-diff_PCIE"
      ],
      "/M.2/PCIe_{C1x1}.TX6-": [
        "85Ohm-diff_PCIE"
      ],
      "/M.2/PCIe_{C1x1}.TX7+": [
        "85Ohm-diff_PCIE"
      ],
      "/M.2/PCIe_{C1x1}.TX7-": [
        "85Ohm-diff_PCIE"
      ],
      "/M.2/PCIe_{C1x1}.~{CLKREQ}": [
        "85Ohm-diff_PCIE"
      ],
      "/M.2/PCIe_{C1x1}.~{RST}": [
        "85Ohm-diff_PCIE"
      ],
      "/M.2/PCIe_{C1x1}{PCIe}": [
        "85Ohm-diff_PCIE"
      ],
      "/M.2/PCIe_{C5x4}.CLK+": [
        "85Ohm-diff_PCIE"
      ],
      "/M.2/PCIe_{C5x4}.CLK-": [
        "85Ohm-diff_PCIE"
      ],
      "/M.2/PCIe_{C5x4}.RX0+": [
        "85Ohm-diff_PCIE"
      ],
      "/M.2/PCIe_{C5x4}.RX0-": [
        "85Ohm-diff_PCIE"
      ],
      "/M.2/PCIe_{C5x4}.RX1+": [
        "85Ohm-diff_PCIE"
      ],
      "/M.2/PCIe_{C5x4}.RX1-": [
        "85Ohm-diff_PCIE"
      ],
      "/M.2/PCIe_{C5x4}.RX2+": [
        "85Ohm-diff_PCIE"
      ],
      "/M.2/PCIe_{C5x4}.RX2-": [
        "85Ohm-diff_PCIE"
      ],
      "/M.2/PCIe_{C5x4}.RX3+": [
        "85Ohm-diff_PCIE"
      ],
      "/M.2/PCIe_{C5x4}.RX3-": [
        "85Ohm-diff_PCIE"
      ],
      "/M.2/PCIe_{C5x4}.TX0+": [
        "85Ohm-diff_PCIE"
      ],
      "/M.2/PCIe_{C5x4}.TX0-": [
        "85Ohm-diff_PCIE"
      ],
      "/M.2/PCIe_{C5x4}.TX1+": [
        "85Ohm-diff_PCIE"
      ],
      "/M.2/PCIe_{C5x4}.TX1-": [
        "85Ohm-diff_PCIE"
      ],
      "/M.2/PCIe_{C5x4}.TX2+": [
        "85Ohm-diff_PCIE"
      ],
      "/M.2/PCIe_{C5x4}.TX2-": [
        "85Ohm-diff_PCIE"
      ],
      "/M.2/PCIe_{C5x4}.TX3+": [
        "85Ohm-diff_PCIE"
      ],
      "/M.2/PCIe_{C5x4}.TX3-": [
        "85Ohm-diff_PCIE"
      ],
      "/M.2/USB3.D+": [
        "90Ohm-diff_USB_2.0"
      ],
      "/M.2/USB3.D-": [
        "90Ohm-diff_USB_2.0"
      ],
      "/M.2/USB3{USB}": [
        "90Ohm-diff_USB_2.0"
      ],
      "/M.2/WIFI_BT_USB_D_N": [
        "90Ohm-diff_USB_2.0"
      ],
      "/M.2/WIFI_BT_USB_D_P": [
        "90Ohm-diff_USB_2.0"
      ],
      "/Recovery USB/USB0.D+": [
        "90Ohm-diff_USB_2.0"
      ],
      "/Recovery USB/USB0.D-": [
        "90Ohm-diff_USB_2.0"
      ],
      "/Recovery USB/USBC2_CONN_TX1_N": [
        "85Ohm-diff_USB_SS"
      ],
      "/Recovery USB/USBC2_CONN_TX1_P": [
        "85Ohm-diff_USB_SS"
      ],
      "/Recovery USB/USBC2_CONN_TX2_N": [
        "85Ohm-diff_USB_SS"
      ],
      "/Recovery USB/USBC2_CONN_TX2_P": [
        "85Ohm-diff_USB_SS"
      ],
      "/Recovery USB/USBC2_RX1_N": [
        "85Ohm-diff_USB_SS"
      ],
      "/Recovery USB/USBC2_RX1_P": [
        "85Ohm-diff_USB_SS"
      ],
      "/Recovery USB/USBC2_RX2_N": [
        "85Ohm-diff_USB_SS"
      ],
      "/Recovery USB/USBC2_RX2_P": [
        "85Ohm-diff_USB_SS"
      ],
      "/Recovery USB/USBC2_TX1_N": [
        "85Ohm-diff_USB_SS"
      ],
      "/Recovery USB/USBC2_TX1_P": [
        "85Ohm-diff_USB_SS"
      ],
      "/Recovery USB/USBC2_TX2_N": [
        "85Ohm-diff_USB_SS"
      ],
      "/Recovery USB/USBC2_TX2_P": [
        "85Ohm-diff_USB_SS"
      ],
      "/Recovery USB/USBSS0.RX+": [
        "85Ohm-diff_USB_SS"
      ],
      "/Recovery USB/USBSS0.RX-": [
        "85Ohm-diff_USB_SS"
      ],
      "/Recovery USB/USBSS0.TX+": [
        "85Ohm-diff_USB_SS"
      ],
      "/Recovery USB/USBSS0.TX-": [
        "85Ohm-diff_USB_SS"
      ],
      "/Recovery USB/USBSS_RX_N": [
        "85Ohm-diff_USB_SS"
      ],
      "/Recovery USB/USBSS_RX_P": [
        "85Ohm-diff_USB_SS"
      ],
      "/Recovery USB/USBSS_TX_N": [
        "85Ohm-diff_USB_SS"
      ],
      "/Recovery USB/USBSS_TX_P": [
        "85Ohm-diff_USB_SS"
      ],
      "/SFP/SFI.RX+": [
        "85Ohm-diff_SFI"
      ],
      "/SFP/SFI.RX-": [
        "85Ohm-diff_SFI"
      ],
      "/SFP/SFI.TX+": [
        "85Ohm-diff_SFI"
      ],
      "/SFP/SFI.TX-": [
        "85Ohm-diff_SFI"
      ],
      "/SFP/SFI_CONN_RX_N": [
        "85Ohm-diff_SFI"
      ],
      "/SFP/SFI_CONN_RX_P": [
        "85Ohm-diff_SFI"
      ],
      "/SFP/SFI_CONN_TX_N": [
        "85Ohm-diff_SFI"
      ],
      "/SFP/SFI_CONN_TX_P": [
        "85Ohm-diff_SFI"
      ],
      "/SoM_IO2/C2_REFCLK+": [
        "85Ohm-diff_PCIE"
      ],
      "/SoM_IO2/C2_REFCLK-": [
        "85Ohm-diff_PCIE"
      ],
      "/SoM_IO2/DP0.AUX+": [
        "85Ohm-diff_DP"
      ],
      "/SoM_IO2/DP0.AUX-": [
        "85Ohm-diff_DP"
      ],
      "/SoM_IO2/DP0.AUX_C+": [
        "85Ohm-diff_DP"
      ],
      "/SoM_IO2/DP0.AUX_C-": [
        "85Ohm-diff_DP"
      ],
      "/SoM_IO2/DP0.HPD": [
        "85Ohm-diff_DP"
      ],
      "/SoM_IO2/DP0.TX0+": [
        "85Ohm-diff_DP"
      ],
      "/SoM_IO2/DP0.TX0-": [
        "85Ohm-diff_DP"
      ],
      "/SoM_IO2/DP0.TX0_C+": [
        "85Ohm-diff_DP"
      ],
      "/SoM_IO2/DP0.TX0_C-": [
        "85Ohm-diff_DP"
      ],
      "/SoM_IO2/DP0.TX1+": [
        "85Ohm-diff_DP"
      ],
      "/SoM_IO2/DP0.TX1-": [
        "85Ohm-diff_DP"
      ],
      "/SoM_IO2/DP0.TX1_C+": [
        "85Ohm-diff_DP"
      ],
      "/SoM_IO2/DP0.TX1_C-": [
        "85Ohm-diff_DP"
      ],
      "/SoM_IO2/DP0.TX2+": [
        "85Ohm-diff_DP"
      ],
      "/SoM_IO2/DP0.TX2-": [
        "85Ohm-diff_DP"
      ],
      "/SoM_IO2/DP0.TX2_C+": [
        "85Ohm-diff_DP"
      ],
      "/SoM_IO2/DP0.TX2_C-": [
        "85Ohm-diff_DP"
      ],
      "/SoM_IO2/DP0.TX3+": [
        "85Ohm-diff_DP"
      ],
      "/SoM_IO2/DP0.TX3-": [
        "85Ohm-diff_DP"
      ],
      "/SoM_IO2/DP0.TX3_C+": [
        "85Ohm-diff_DP"
      ],
      "/SoM_IO2/DP0.TX3_C-": [
        "85Ohm-diff_DP"
      ],
      "/SoM_IO2/DP1.AUX_C+": [
        "85Ohm-diff_DP"
      ],
      "/SoM_IO2/DP1.AUX_C-": [
        "85Ohm-diff_DP"
      ],
      "/SoM_IO2/DP1.TX0_C+": [
        "85Ohm-diff_DP"
      ],
      "/SoM_IO2/DP1.TX0_C-": [
        "85Ohm-diff_DP"
      ],
      "/SoM_IO2/DP1.TX1_C+": [
        "85Ohm-diff_DP"
      ],
      "/SoM_IO2/DP1.TX1_C-": [
        "85Ohm-diff_DP"
      ],
      "/SoM_IO2/DP1.TX2_C+": [
        "85Ohm-diff_DP"
      ],
      "/SoM_IO2/DP1.TX2_C-": [
        "85Ohm-diff_DP"
      ],
      "/SoM_IO2/DP1.TX3_C+": [
        "85Ohm-diff_DP"
      ],
      "/SoM_IO2/DP1.TX3_C-": [
        "85Ohm-diff_DP"
      ],
      "/SoM_IO2/DP2.AUX_C+": [
        "85Ohm-diff_DP"
      ],
      "/SoM_IO2/DP2.AUX_C-": [
        "85Ohm-diff_DP"
      ],
      "/SoM_IO2/DP2.TX0_C+": [
        "85Ohm-diff_DP"
      ],
      "/SoM_IO2/DP2.TX0_C-": [
        "85Ohm-diff_DP"
      ],
      "/SoM_IO2/DP2.TX1_C+": [
        "85Ohm-diff_DP"
      ],
      "/SoM_IO2/DP2.TX1_C-": [
        "85Ohm-diff_DP"
      ],
      "/SoM_IO2/DP2.TX2_C+": [
        "85Ohm-diff_DP"
      ],
      "/SoM_IO2/DP2.TX2_C-": [
        "85Ohm-diff_DP"
      ],
      "/SoM_IO2/DP2.TX3_C+": [
        "85Ohm-diff_DP"
      ],
      "/SoM_IO2/DP2.TX3_C-": [
        "85Ohm-diff_DP"
      ],
      "/SoM_IO2/DP3.AUX_C+": [
        "85Ohm-diff_DP"
      ],
      "/SoM_IO2/DP3.AUX_C-": [
        "85Ohm-diff_DP"
      ],
      "/SoM_IO2/DP3.TX0_C+": [
        "85Ohm-diff_DP"
      ],
      "/SoM_IO2/DP3.TX0_C-": [
        "85Ohm-diff_DP"
      ],
      "/SoM_IO2/DP3.TX1_C+": [
        "85Ohm-diff_DP"
      ],
      "/SoM_IO2/DP3.TX1_C-": [
        "85Ohm-diff_DP"
      ],
      "/SoM_IO2/DP3.TX2_C+": [
        "85Ohm-diff_DP"
      ],
      "/SoM_IO2/DP3.TX2_C-": [
        "85Ohm-diff_DP"
      ],
      "/SoM_IO2/DP3.TX3_C+": [
        "85Ohm-diff_DP"
      ],
      "/SoM_IO2/DP3.TX3_C-": [
        "85Ohm-diff_DP"
      ],
      "/SoM_IO2/PCIe_{C2x1}R_CLK+": [
        "85Ohm-diff_PCIE"
      ],
      "/SoM_IO2/PCIe_{C2x1}R_CLK-": [
        "85Ohm-diff_PCIE"
      ],
      "/SoM_IO2/SFI_CLK+": [
        "85Ohm-diff_SFI"
      ],
      "/SoM_IO2/SFI_CLK-": [
        "85Ohm-diff_SFI"
      ],
      "/SoM_IO2/SFI_REFCLK+": [
        "85Ohm-diff_SFI"
      ],
      "/SoM_IO2/SFI_REFCLK-": [
        "85Ohm-diff_SFI"
      ],
      "/SoM_IO2/USB1.D+": [
        "90Ohm-diff_USB_2.0"
      ],
      "/SoM_IO2/USB1.D-": [
        "90Ohm-diff_USB_2.0"
      ],
      "/SoM_IO2/USB2.D+": [
        "90Ohm-diff_USB_2.0"
      ],
      "/SoM_IO2/USB2.D-": [
        "90Ohm-diff_USB_2.0"
      ],
      "/SoM_IO2/USBSS1.RX+": [
        "85Ohm-diff_USB_SS"
      ],
      "/SoM_IO2/USBSS1.RX-": [
        "85Ohm-diff_USB_SS"
      ],
      "/SoM_IO2/USBSS1.TX+": [
        "85Ohm-diff_USB_SS"
      ],
      "/SoM_IO2/USBSS1.TX-": [
        "85Ohm-diff_USB_SS"
      ],
      "/SoM_IO2/USBSS2.RX+": [
        "85Ohm-diff_USB_SS"
      ],
      "/SoM_IO2/USBSS2.RX-": [
        "85Ohm-diff_USB_SS"
      ],
      "/SoM_IO2/USBSS2.TX+": [
        "85Ohm-diff_USB_SS"
      ],
      "/SoM_IO2/USBSS2.TX-": [
        "85Ohm-diff_USB_SS"
      ],
      "/USB DP Alt mode/USBC1_CONN_TX1_N": [
        "85Ohm-diff_USB_SS"
      ],
      "/USB DP Alt mode/USBC1_CONN_TX1_P": [
        "85Ohm-diff_USB_SS"
      ],
      "/USB DP Alt mode/USBC1_CONN_TX2_N": [
        "85Ohm-diff_USB_SS"
      ],
      "/USB DP Alt mode/USBC1_CONN_TX2_P": [
        "85Ohm-diff_USB_SS"
      ],
      "/USB DP Alt mode/USBC1_RX1_N": [
        "85Ohm-diff_USB_SS"
      ],
      "/USB DP Alt mode/USBC1_RX1_P": [
        "85Ohm-diff_USB_SS"
      ],
      "/USB DP Alt mode/USBC1_RX2_N": [
        "85Ohm-diff_USB_SS"
      ],
      "/USB DP Alt mode/USBC1_RX2_P": [
        "85Ohm-diff_USB_SS"
      ],
      "/USB DP Alt mode/USBC1_SBU_N": [
        "85Ohm-diff_USB_SS"
      ],
      "/USB DP Alt mode/USBC1_SBU_P": [
        "85Ohm-diff_USB_SS"
      ],
      "/USB DP Alt mode/USBC1_TX1_N": [
        "85Ohm-diff_USB_SS"
      ],
      "/USB DP Alt mode/USBC1_TX1_P": [
        "85Ohm-diff_USB_SS"
      ],
      "/USB DP Alt mode/USBC1_TX2_N": [
        "85Ohm-diff_USB_SS"
      ],
      "/USB DP Alt mode/USBC1_TX2_P": [
        "85Ohm-diff_USB_SS"
      ],
      "/USB DP Alt mode/USBSS1_RX_C_N": [
        "85Ohm-diff_USB_SS"
      ],
      "/USB DP Alt mode/USBSS1_RX_C_P": [
        "85Ohm-diff_USB_SS"
      ],
      "/USB DP Alt mode/USBSS1_TX_C_N": [
        "85Ohm-diff_USB_SS"
      ],
      "/USB DP Alt mode/USBSS1_TX_C_P": [
        "85Ohm-diff_USB_SS"
      ],
      "/USB Debug, PD/USBC0_D_N": [
        "90Ohm-diff_USB_2.0"
      ],
      "/USB Debug, PD/USBC0_D_P": [
        "90Ohm-diff_USB_2.0"
      ],
      "/USB Debug, PD/USB_FTDI_N": [
        "90Ohm-diff_USB_2.0"
      ],
      "/USB Debug, PD/USB_FTDI_P": [
        "90Ohm-diff_USB_2.0"
      ],
      "/USB Hub/USBC3_CONN_TX1_N": [
        "85Ohm-diff_USB_SS"
      ],
      "/USB Hub/USBC3_CONN_TX1_P": [
        "85Ohm-diff_USB_SS"
      ],
      "/USB Hub/USBC3_CONN_TX2_N": [
        "85Ohm-diff_USB_SS"
      ],
      "/USB Hub/USBC3_CONN_TX2_P": [
        "85Ohm-diff_USB_SS"
      ],
      "/USB Hub/USBC3_D+": [
        "90Ohm-diff_USB_2.0"
      ],
      "/USB Hub/USBC3_D-": [
        "90Ohm-diff_USB_2.0"
      ],
      "/USB Hub/USBC3_RX_{1}+": [
        "85Ohm-diff_USB_SS"
      ],
      "/USB Hub/USBC3_RX_{1}-": [
        "85Ohm-diff_USB_SS"
      ],
      "/USB Hub/USBC3_RX_{2}+": [
        "85Ohm-diff_USB_SS"
      ],
      "/USB Hub/USBC3_RX_{2}-": [
        "85Ohm-diff_USB_SS"
      ],
      "/USB Hub/USBC3_TX_{1}+": [
        "85Ohm-diff_USB_SS"
      ],
      "/USB Hub/USBC3_TX_{1}-": [
        "85Ohm-diff_USB_SS"
      ],
      "/USB Hub/USBC3_TX_{2}+": [
        "85Ohm-diff_USB_SS"
      ],
      "/USB Hub/USBC3_TX_{2}-": [
        "85Ohm-diff_USB_SS"
      ],
      "/USB Hub/USBC4_CONN_TX1_N": [
        "85Ohm-diff_USB_SS"
      ],
      "/USB Hub/USBC4_CONN_TX1_P": [
        "85Ohm-diff_USB_SS"
      ],
      "/USB Hub/USBC4_CONN_TX2_N": [
        "85Ohm-diff_USB_SS"
      ],
      "/USB Hub/USBC4_CONN_TX2_P": [
        "85Ohm-diff_USB_SS"
      ],
      "/USB Hub/USBC4_D+": [
        "90Ohm-diff_USB_2.0"
      ],
      "/USB Hub/USBC4_D-": [
        "90Ohm-diff_USB_2.0"
      ],
      "/USB Hub/USBC4_RX_{1}+": [
        "85Ohm-diff_USB_SS"
      ],
      "/USB Hub/USBC4_RX_{1}-": [
        "85Ohm-diff_USB_SS"
      ],
      "/USB Hub/USBC4_RX_{2}+": [
        "85Ohm-diff_USB_SS"
      ],
      "/USB Hub/USBC4_RX_{2}-": [
        "85Ohm-diff_USB_SS"
      ],
      "/USB Hub/USBC4_TX_{1}+": [
        "85Ohm-diff_USB_SS"
      ],
      "/USB Hub/USBC4_TX_{1}-": [
        "85Ohm-diff_USB_SS"
      ],
      "/USB Hub/USBC4_TX_{2}+": [
        "85Ohm-diff_USB_SS"
      ],
      "/USB Hub/USBC4_TX_{2}-": [
        "85Ohm-diff_USB_SS"
      ],
      "/USB Hub/USBSS_RX_N": [
        "85Ohm-diff_USB_SS"
      ],
      "/USB Hub/USBSS_RX_P": [
        "85Ohm-diff_USB_SS"
      ],
      "/USB Hub/USBSS_TX_N": [
        "85Ohm-diff_USB_SS"
      ],
      "/USB Hub/USBSS_TX_P": [
        "85Ohm-diff_USB_SS"
      ],
      "/USB Hub/VBUS_MON_UP": [
        "85Ohm-diff_USB_SS"
      ],
      "Net-(U21-VBUS_MON_UP)": [
        "85Ohm-diff_USB_SS"
      ],
      "unconnected-(C253-Pad1)": [
        "85Ohm-diff_USB_SS"
      ],
      "unconnected-(C254-Pad1)": [
        "85Ohm-diff_USB_SS"
      ],
      "unconnected-(C255-Pad1)": [
        "85Ohm-diff_USB_SS"
      ],
      "unconnected-(C256-Pad1)": [
        "85Ohm-diff_USB_SS"
      ]
    },
    "netclass_patterns": []
  },
  "pcbnew": {
    "last_paths": {
      "gencad": "",
      "idf": "",
      "netlist": "",
      "plot": "",
      "pos_files": "",
      "specctra_dsn": "",
      "step": "",
      "svg": "",
      "vrml": ""
    },
    "page_layout_descr_file": ""
  },
  "schematic": {
    "annotate_start_num": 0,
    "bom_export_filename": "${PROJECTNAME}.csv",
    "bom_fmt_presets": [],
    "bom_fmt_settings": {
      "field_delimiter": ",",
      "keep_line_breaks": false,
      "keep_tabs": false,
      "name": "CSV",
      "ref_delimiter": ",",
      "ref_range_delimiter": "",
      "string_delimiter": "\""
    },
    "bom_presets": [],
    "bom_settings": {
      "exclude_dnp": true,
      "fields_ordered": [
        {
          "group_by": false,
          "label": "Reference",
          "name": "Reference",
          "show": true
        },
        {
          "group_by": false,
          "label": "Qty",
          "name": "${QUANTITY}",
          "show": true
        },
        {
          "group_by": true,
          "label": "Value",
          "name": "Value",
          "show": true
        },
        {
          "group_by": false,
          "label": "DNP",
          "name": "${DNP}",
          "show": false
        },
        {
          "group_by": false,
          "label": "Exclude from BOM",
          "name": "${EXCLUDE_FROM_BOM}",
          "show": false
        },
        {
          "group_by": false,
          "label": "Exclude from Board",
          "name": "${EXCLUDE_FROM_BOARD}",
          "show": false
        },
        {
          "group_by": true,
          "label": "Footprint",
          "name": "Footprint",
          "show": true
        },
        {
          "group_by": false,
          "label": "Datasheet",
          "name": "Datasheet",
          "show": true
        },
        {
          "group_by": false,
          "label": "Color",
          "name": "Color",
          "show": false
        },
        {
          "group_by": false,
          "label": "Current",
          "name": "Current",
          "show": false
        },
        {
          "group_by": false,
          "label": "Dielectric",
          "name": "Dielectric",
          "show": false
        },
        {
          "group_by": false,
          "label": "Displayed name",
          "name": "Displayed name",
          "show": false
        },
        {
          "group_by": false,
          "label": "IMax",
          "name": "IMax",
          "show": false
        },
        {
          "group_by": false,
          "label": "ISat",
          "name": "ISat",
          "show": false
        },
        {
          "group_by": false,
          "label": "License",
          "name": "License",
          "show": false
        },
        {
          "group_by": false,
          "label": "MPN",
          "name": "MPN",
          "show": false
        },
        {
          "group_by": false,
          "label": "Manufacturer",
          "name": "Manufacturer",
          "show": false
        },
        {
          "group_by": false,
          "label": "Max. Curr.",
          "name": "Max. Curr.",
          "show": false
        },
        {
          "group_by": false,
          "label": "Public",
          "name": "Public",
          "show": false
        },
        {
          "group_by": false,
          "label": "Size",
          "name": "Size",
          "show": false
        },
        {
          "group_by": false,
          "label": "Tolerance",
          "name": "Tolerance",
          "show": false
        },
        {
          "group_by": false,
          "label": "Val",
          "name": "Val",
          "show": false
        },
        {
          "group_by": false,
          "label": "Voltage",
          "name": "Voltage",
          "show": false
        },
        {
          "group_by": false,
          "label": "Author",
          "name": "Author",
          "show": false
        },
        {
          "group_by": false,
          "label": "Description",
          "name": "Description",
          "show": false
        },
        {
          "group_by": false,
          "label": "#",
          "name": "${ITEM_NUMBER}",
          "show": false
        }
      ],
      "filter_string": "",
      "group_symbols": true,
      "include_excluded_from_bom": true,
      "name": "",
      "sort_asc": true,
      "sort_field": "Value"
    },
    "connection_grid_size": 50.0,
    "drawing": {
      "dashed_lines_dash_length_ratio": 12.0,
      "dashed_lines_gap_length_ratio": 3.0,
      "default_line_thickness": 6.0,
      "default_text_size": 50.0,
      "field_names": [],
      "intersheets_ref_own_page": false,
      "intersheets_ref_prefix": "",
      "intersheets_ref_short": false,
      "intersheets_ref_show": false,
      "intersheets_ref_suffix": "",
      "junction_size_choice": 3,
      "label_size_ratio": 0.375,
      "operating_point_overlay_i_precision": 3,
      "operating_point_overlay_i_range": "~A",
      "operating_point_overlay_v_precision": 3,
      "operating_point_overlay_v_range": "~V",
      "overbar_offset_ratio": 1.23,
      "pin_symbol_size": 25.0,
      "text_offset_ratio": 0.15
    },
    "legacy_lib_dir": "",
    "legacy_lib_list": [],
    "meta": {
      "version": 1
    },
    "net_format_name": "",
    "ngspice": {
      "fix_include_paths": true,
      "meta": {
        "version": 0
      },
      "model_mode": 4,
      "workbook_filename": ""
    },
    "page_layout_descr_file": "",
    "plot_directory": "",
    "space_save_all_events": true,
    "spice_current_sheet_as_root": false,
    "spice_external_command": "spice \"%I\"",
    "spice_model_current_sheet_as_root": true,
    "spice_save_all_currents": false,
    "spice_save_all_dissipations": false,
    "spice_save_all_voltages": false,
    "subpart_first_id": 65,
    "subpart_id_separator": 0
  },
  "sheets": [
    [
      "",
      "Root"
    ],
    [
      "",
      "SoM_IO"
    ],
    [
      "",
      "SoM_IO2"
    ],
    [
      "",
      "SoM_Power"
    ],
    [
      "",
      "Power"
    ],
    [
      "",
      "USB Hub"
    ],
    [
      "",
      "Recovery USB"
    ],
    [
      "",
      "USB DP Alt mode"
    ],
    [
      "",
      "USB Debug, PD"
    ],
    [
      "",
      "CSI"
    ],
    [
      "",
      "SFP"
    ],
    [
      "",
      "M.2"
    ],
    [
      "",
      "Peripherals"
    ],
    [
      "",
      "Expansion connector"
    ],
    [
      "",
      "DCDC"
    ]
  ],
  "text_variables": {}
}
